(kicad_pcb
	(version 20260206)
	(generator "pcbnew")
	(generator_version "10.0")
	(general
		(thickness 1.6)
		(legacy_teardrops no)
	)
	(paper "A4")
	(title_block
		(title "9052_F0T_PDB_Converter_Brick_F_V03_1208_1600_OCP.brd")
		(comment 1 "Grand Teton / footprints 186-190 of 578")
	)
	(layers
		(0 "F.Cu" signal "TOP")
		(4 "In1.Cu" signal "GND")
		(6 "In2.Cu" signal "IN1")
		(8 "In3.Cu" signal "GND1")
		(10 "In4.Cu" signal "VCC")
		(12 "In5.Cu" signal "VCC1")
		(14 "In6.Cu" signal "GND2")
		(16 "In7.Cu" signal "IN2")
		(18 "In8.Cu" signal "GND3")
		(2 "B.Cu" signal "BOTTOM")
		(9 "F.Adhes" user "F.Adhesive")
		(11 "B.Adhes" user "B.Adhesive")
		(13 "F.Paste" user "Package Geometry/Pastemask Top")
		(15 "B.Paste" user "Package Geometry/Pastemask Bottom")
		(5 "F.SilkS" user "Ref Des/Silkscreen Top")
		(7 "B.SilkS" user "Ref Des/Silkscreen Bottom")
		(1 "F.Mask" user "Board Geometry/Soldermask Top")
		(3 "B.Mask" user "Board Geometry/Soldermask Bottom")
		(17 "Dwgs.User" user "User.Drawings")
		(19 "Cmts.User" user "User.Comments")
		(21 "Eco1.User" user "User.Eco1")
		(23 "Eco2.User" user "User.Eco2")
		(25 "Edge.Cuts" user "Board Geometry/Outline")
		(27 "Margin" user)
		(31 "F.CrtYd" user "Package Geometry/Place Bound Top")
		(29 "B.CrtYd" user "Package Geometry/Place Bound Bottom")
		(35 "F.Fab" user "Ref Des/Assembly Top")
		(33 "B.Fab" user "Ref Des/Assembly Bottom")
	)
	(footprint ""
		(layer "F.Cu")
		(at 41.6814 -57.4548 180)
		(property "Reference" "U32"
			(at 2.3495 -4.91617 0)
			(unlocked yes)
			(layer "F.SilkS")
			(effects
				(font
					(size 0.7874 0.5842)
					(thickness 0.1524)
				)
				(justify left)
			)
		)
		(property "Value" ""
			(at 0 0 180)
			(layer "F.Fab")
			(effects
				(font
					(size 1.27 1.27)
				)
			)
		)
		(duplicate_pad_numbers_are_jumpers no)
		(fp_line
			(start 1.549908 2.549906)
			(end 1.549908 2.253996)
			(stroke
				(width 0.1524)
				(type default)
			)
			(layer "F.SilkS")
		)
		(fp_line
			(start 1.549908 -2.253996)
			(end 1.549908 -2.549906)
			(stroke
				(width 0.1524)
				(type default)
			)
			(layer "F.SilkS")
		)
		(fp_line
			(start 1.549908 -2.549906)
			(end 0.752094 -2.549906)
			(stroke
				(width 0.1524)
				(type default)
			)
			(layer "F.SilkS")
		)
		(fp_line
			(start 0.753872 2.549906)
			(end 1.549908 2.549906)
			(stroke
				(width 0.1524)
				(type default)
			)
			(layer "F.SilkS")
		)
		(fp_line
			(start 0.2413 -2.549906)
			(end -0.2413 -2.549906)
			(stroke
				(width 0.1524)
				(type default)
			)
			(layer "F.SilkS")
		)
		(fp_line
			(start -0.245872 2.549906)
			(end 0.245872 2.549906)
			(stroke
				(width 0.1524)
				(type default)
			)
			(layer "F.SilkS")
		)
		(fp_line
			(start -0.752094 -2.549906)
			(end -1.549908 -2.549906)
			(stroke
				(width 0.1524)
				(type default)
			)
			(layer "F.SilkS")
		)
		(fp_line
			(start -1.549908 2.549906)
			(end -0.753872 2.549906)
			(stroke
				(width 0.1524)
				(type default)
			)
			(layer "F.SilkS")
		)
		(fp_line
			(start -1.549908 2.253996)
			(end -1.549908 2.549906)
			(stroke
				(width 0.1524)
				(type default)
			)
			(layer "F.SilkS")
		)
		(fp_line
			(start -1.549908 -2.549906)
			(end -1.549908 -2.251964)
			(stroke
				(width 0.1524)
				(type default)
			)
			(layer "F.SilkS")
		)
		(fp_poly
			(pts
				(xy -1.95961 -2.28981) (xy -2.862834 -2.591054) (xy -2.260854 -3.193034)
			)
			(stroke
				(width 0)
				(type default)
			)
			(fill yes)
			(layer "F.SilkS")
		)
		(fp_line
			(start 1.549908 2.549906)
			(end 1.549908 -2.549906)
			(stroke
				(width 0.1)
				(type default)
			)
			(layer "F.Fab")
		)
		(fp_line
			(start 1.549908 -2.549906)
			(end -1.549908 -2.549906)
			(stroke
				(width 0.1)
				(type default)
			)
			(layer "F.Fab")
		)
		(fp_line
			(start -1.549908 2.549906)
			(end 1.549908 2.549906)
			(stroke
				(width 0.1)
				(type default)
			)
			(layer "F.Fab")
		)
		(fp_line
			(start -1.549908 -2.549906)
			(end -1.549908 2.549906)
			(stroke
				(width 0.1)
				(type default)
			)
			(layer "F.Fab")
		)
		(fp_poly
			(pts
				(xy -1.891538 -1.999996) (xy -2.7432 -1.574292) (xy -2.7432 -2.4257)
			)
			(stroke
				(width 0)
				(type default)
			)
			(fill yes)
			(layer "F.Fab")
		)
		(fp_text user "12"
			(at 3.16865 5.0292 90)
			(unlocked yes)
			(layer "F.SilkS")
			(effects
				(font
					(size 0.635 0.4064)
					(thickness 0.1524)
				)
			)
		)
		(fp_text user "20"
			(at 2.91465 -3.7338 90)
			(unlocked yes)
			(layer "F.SilkS")
			(effects
				(font
					(size 0.635 0.4064)
					(thickness 0.1524)
				)
			)
		)
		(fp_text user "11"
			(at 2.3114 6.07695 180)
			(unlocked yes)
			(layer "F.SilkS")
			(effects
				(font
					(size 0.635 0.4064)
					(thickness 0.1524)
				)
			)
		)
		(fp_text user "21_22"
			(at -0.0762 -3.401568 180)
			(unlocked yes)
			(layer "F.SilkS")
			(effects
				(font
					(size 0.635 0.4064)
					(thickness 0.1524)
				)
			)
		)
		(fp_text user "10"
			(at -1.4224 3.253232 180)
			(unlocked yes)
			(layer "F.SilkS")
			(effects
				(font
					(size 0.635 0.4064)
					(thickness 0.1524)
				)
			)
		)
		(fp_text user "9"
			(at -2.338832 2.5908 90)
			(unlocked yes)
			(layer "F.SilkS")
			(effects
				(font
					(size 0.635 0.4064)
					(thickness 0.1524)
				)
			)
		)
		(fp_text user "12"
			(at 2.207768 2.7178 90)
			(unlocked yes)
			(layer "F.Fab")
			(effects
				(font
					(size 0.635 0.4064)
					(thickness 0.1524)
				)
			)
		)
		(fp_text user "20"
			(at 2.055368 -2.7686 90)
			(unlocked yes)
			(layer "F.Fab")
			(effects
				(font
					(size 0.635 0.4064)
					(thickness 0.1524)
				)
			)
		)
		(fp_text user "11"
			(at 1.1938 3.329432 180)
			(unlocked yes)
			(layer "F.Fab")
			(effects
				(font
					(size 0.635 0.4064)
					(thickness 0.1524)
				)
			)
		)
		(fp_text user "21_22"
			(at -0.0762 -3.401568 180)
			(unlocked yes)
			(layer "F.Fab")
			(effects
				(font
					(size 0.635 0.4064)
					(thickness 0.1524)
				)
			)
		)
		(fp_text user "10"
			(at -1.4224 3.253232 180)
			(unlocked yes)
			(layer "F.Fab")
			(effects
				(font
					(size 0.635 0.4064)
					(thickness 0.1524)
				)
			)
		)
		(fp_text user "9"
			(at -2.338832 2.5908 90)
			(unlocked yes)
			(layer "F.Fab")
			(effects
				(font
					(size 0.635 0.4064)
					(thickness 0.1524)
				)
			)
		)
		(pad "1" smd circle
			(at -1.374902 -1.999996 90)
			(size 0 0)
			(layers "F.Cu" "F.Mask" "F.Paste")
			(net "P12V_HPDB_0_EN_R")
		)
		(pad "2" smd rect
			(at -1.400048 -1.500124 90)
			(size 0.254 0.8128)
			(layers "F.Cu" "F.Mask" "F.Paste")
			(net "GND")
		)
		(pad "3" smd rect
			(at -1.400048 -0.999998 90)
			(size 0.254 0.8128)
			(layers "F.Cu" "F.Mask" "F.Paste")
			(net "GND")
		)
		(pad "4" smd rect
			(at -1.400048 -0.499872 90)
			(size 0.254 0.8128)
			(layers "F.Cu" "F.Mask" "F.Paste")
			(net "P12V_HPDB_0_TIMER")
		)
		(pad "5" smd rect
			(at -1.400048 0 90)
			(size 0.254 0.8128)
			(layers "F.Cu" "F.Mask" "F.Paste")
			(net "P12V_HPDB_0_ISET")
		)
		(pad "6" smd rect
			(at -1.400048 0.499872 90)
			(size 0.254 0.8128)
			(layers "F.Cu" "F.Mask" "F.Paste")
			(net "P12V_HPDB_0_SS")
		)
		(pad "7" smd rect
			(at -1.400048 0.999998 90)
			(size 0.254 0.8128)
			(layers "F.Cu" "F.Mask" "F.Paste")
			(net "GND")
		)
		(pad "8" smd rect
			(at -1.400048 1.500124 90)
			(size 0.254 0.8128)
			(layers "F.Cu" "F.Mask" "F.Paste")
			(net "P12V_HPDB_0_IMON")
		)
		(pad "9" smd rect
			(at -1.400048 1.999996 90)
			(size 0.254 0.8128)
			(layers "F.Cu" "F.Mask" "F.Paste")
			(net "P12V_HPDB_0_FLTB")
		)
		(pad "10" smd rect
			(at -0.499872 2.400046 180)
			(size 0.254 0.8128)
			(layers "F.Cu" "F.Mask" "F.Paste")
			(net "P12V_HPDB_PWRGD")
		)
		(pad "11" smd rect
			(at 0.499872 2.400046 180)
			(size 0.254 0.8128)
			(layers "F.Cu" "F.Mask" "F.Paste")
			(net "P12V_HPDB_0_FB")
		)
		(pad "12" smd rect
			(at 1.400048 1.999996 90)
			(size 0.254 0.8128)
			(layers "F.Cu" "F.Mask" "F.Paste")
			(net "P12V_HPDB_0_PD")
		)
		(pad "13" smd rect
			(at 1.400048 1.500124 90)
			(size 0.254 0.8128)
			(layers "F.Cu" "F.Mask" "F.Paste")
			(net "P12V_HPDB")
		)
		(pad "14" smd rect
			(at 1.400048 0.999998 90)
			(size 0.254 0.8128)
			(layers "F.Cu" "F.Mask" "F.Paste")
			(net "P12V_HPDB")
		)
		(pad "15" smd rect
			(at 1.400048 0.499872 90)
			(size 0.254 0.8128)
			(layers "F.Cu" "F.Mask" "F.Paste")
			(net "P12V_HPDB")
		)
		(pad "16" smd rect
			(at 1.400048 0 90)
			(size 0.254 0.8128)
			(layers "F.Cu" "F.Mask" "F.Paste")
			(net "P12V_HPDB")
		)
		(pad "17" smd rect
			(at 1.400048 -0.499872 90)
			(size 0.254 0.8128)
			(layers "F.Cu" "F.Mask" "F.Paste")
			(net "P12V_HPDB")
		)
		(pad "18" smd rect
			(at 1.400048 -0.999998 90)
			(size 0.254 0.8128)
			(layers "F.Cu" "F.Mask" "F.Paste")
			(net "P12V_HPDB")
		)
		(pad "19" smd rect
			(at 1.400048 -1.500124 90)
			(size 0.254 0.8128)
			(layers "F.Cu" "F.Mask" "F.Paste")
			(net "P12V_HPDB")
		)
		(pad "20" smd rect
			(at 1.400048 -1.999996 90)
			(size 0.254 0.8128)
			(layers "F.Cu" "F.Mask" "F.Paste")
			(net "P12V_HPDB")
		)
		(pad "21_22" smd circle
			(at 0.499872 -2.337562 90)
			(size 0 0)
			(layers "F.Cu" "F.Mask" "F.Paste")
			(net "P12V_BRICK")
		)
		(pad "23" smd rect
			(at 0 -1.100074 90)
			(size 0.254 1.27)
			(layers "F.Cu" "F.Mask" "F.Paste")
			(net "P12V_BRICK")
		)
		(pad "24" smd rect
			(at 0 -0.199898 90)
			(size 0.254 1.27)
			(layers "F.Cu" "F.Mask" "F.Paste")
			(net "P12V_BRICK")
		)
		(pad "25" smd rect
			(at 0 0.700024 90)
			(size 0.254 1.27)
			(layers "F.Cu" "F.Mask" "F.Paste")
			(net "P12V_BRICK")
		)
		(pad "26" smd rect
			(at 0 1.599946 90)
			(size 0.254 1.27)
			(layers "F.Cu" "F.Mask" "F.Paste")
			(net "P12V_BRICK")
		)
	)
	(footprint ""
		(layer "F.Cu")
		(at 149.098 -130.175)
		(property "Reference" "PC18"
			(at 0 0 0)
			(layer "F.SilkS")
			(hide yes)
			(effects
				(font
					(size 1.27 1.27)
				)
			)
		)
		(property "Value" ""
			(at 0 0 0)
			(layer "F.Fab")
			(effects
				(font
					(size 1.27 1.27)
				)
			)
		)
		(duplicate_pad_numbers_are_jumpers no)
		(fp_line
			(start -2.2098 -0.9398)
			(end 2.2098 -0.9398)
			(stroke
				(width 0.1524)
				(type default)
			)
			(layer "F.SilkS")
		)
		(fp_line
			(start -2.2098 0.9398)
			(end -2.2098 -0.9398)
			(stroke
				(width 0.1524)
				(type default)
			)
			(layer "F.SilkS")
		)
		(fp_line
			(start 2.2098 -0.9398)
			(end 2.2098 0.9398)
			(stroke
				(width 0.1524)
				(type default)
			)
			(layer "F.SilkS")
		)
		(fp_line
			(start 2.2098 0.9398)
			(end -2.2098 0.9398)
			(stroke
				(width 0.1524)
				(type default)
			)
			(layer "F.SilkS")
		)
		(fp_line
			(start -1.700022 -0.899922)
			(end 1.700022 -0.899922)
			(stroke
				(width 0.1)
				(type default)
			)
			(layer "F.Fab")
		)
		(fp_line
			(start -1.700022 0.899922)
			(end -1.700022 -0.899922)
			(stroke
				(width 0.1)
				(type default)
			)
			(layer "F.Fab")
		)
		(fp_line
			(start 1.700022 -0.899922)
			(end 1.700022 0.899922)
			(stroke
				(width 0.1)
				(type default)
			)
			(layer "F.Fab")
		)
		(fp_line
			(start 1.700022 0.899922)
			(end -1.700022 0.899922)
			(stroke
				(width 0.1)
				(type default)
			)
			(layer "F.Fab")
		)
		(pad "1" smd rect
			(at -1.4732 0 180)
			(size 1.1684 1.5748)
			(layers "F.Cu" "F.Mask" "F.Paste")
			(net "P52V_HS_FILTER")
		)
		(pad "2" smd rect
			(at 1.4732 0 180)
			(size 1.1684 1.5748)
			(layers "F.Cu" "F.Mask" "F.Paste")
			(net "GND")
		)
	)
	(footprint ""
		(layer "F.Cu")
		(at 168.148 -49.911)
		(property "Reference" "PC33"
			(at 0 0 0)
			(layer "F.SilkS")
			(hide yes)
			(effects
				(font
					(size 1.27 1.27)
				)
			)
		)
		(property "Value" ""
			(at 0 0 0)
			(layer "F.Fab")
			(effects
				(font
					(size 1.27 1.27)
				)
			)
		)
		(duplicate_pad_numbers_are_jumpers no)
		(fp_line
			(start -1.524 -0.762)
			(end 1.524 -0.762)
			(stroke
				(width 0.1524)
				(type default)
			)
			(layer "F.SilkS")
		)
		(fp_line
			(start -1.524 0.762)
			(end -1.524 -0.762)
			(stroke
				(width 0.1524)
				(type default)
			)
			(layer "F.SilkS")
		)
		(fp_line
			(start 1.524 -0.762)
			(end 1.524 0.762)
			(stroke
				(width 0.1524)
				(type default)
			)
			(layer "F.SilkS")
		)
		(fp_line
			(start 1.524 0.762)
			(end -1.524 0.762)
			(stroke
				(width 0.1524)
				(type default)
			)
			(layer "F.SilkS")
		)
		(fp_line
			(start -1.1049 -0.724916)
			(end -1.1049 0.724916)
			(stroke
				(width 0.1)
				(type default)
			)
			(layer "F.Fab")
		)
		(fp_line
			(start -1.1049 0.724916)
			(end 1.1049 0.724916)
			(stroke
				(width 0.1)
				(type default)
			)
			(layer "F.Fab")
		)
		(fp_line
			(start 1.1049 -0.724916)
			(end -1.1049 -0.724916)
			(stroke
				(width 0.1)
				(type default)
			)
			(layer "F.Fab")
		)
		(fp_line
			(start 1.1049 0.724916)
			(end 1.1049 -0.724916)
			(stroke
				(width 0.1)
				(type default)
			)
			(layer "F.Fab")
		)
		(pad "1" smd rect
			(at -0.889 0 180)
			(size 1.016 1.27)
			(layers "F.Cu" "F.Mask" "F.Paste")
			(net "P12V_BRICK")
		)
		(pad "2" smd rect
			(at 0.889 0 180)
			(size 1.016 1.27)
			(layers "F.Cu" "F.Mask" "F.Paste")
			(net "GND")
		)
	)
	(footprint ""
		(layer "F.Cu")
		(at 136.906 -130.175)
		(property "Reference" "PC21"
			(at 0 0 0)
			(layer "F.SilkS")
			(hide yes)
			(effects
				(font
					(size 1.27 1.27)
				)
			)
		)
		(property "Value" ""
			(at 0 0 0)
			(layer "F.Fab")
			(effects
				(font
					(size 1.27 1.27)
				)
			)
		)
		(duplicate_pad_numbers_are_jumpers no)
		(fp_line
			(start -2.2098 -0.9398)
			(end 2.2098 -0.9398)
			(stroke
				(width 0.1524)
				(type default)
			)
			(layer "F.SilkS")
		)
		(fp_line
			(start -2.2098 0.9398)
			(end -2.2098 -0.9398)
			(stroke
				(width 0.1524)
				(type default)
			)
			(layer "F.SilkS")
		)
		(fp_line
			(start 2.2098 -0.9398)
			(end 2.2098 0.9398)
			(stroke
				(width 0.1524)
				(type default)
			)
			(layer "F.SilkS")
		)
		(fp_line
			(start 2.2098 0.9398)
			(end -2.2098 0.9398)
			(stroke
				(width 0.1524)
				(type default)
			)
			(layer "F.SilkS")
		)
		(fp_line
			(start -1.700022 -0.899922)
			(end 1.700022 -0.899922)
			(stroke
				(width 0.1)
				(type default)
			)
			(layer "F.Fab")
		)
		(fp_line
			(start -1.700022 0.899922)
			(end -1.700022 -0.899922)
			(stroke
				(width 0.1)
				(type default)
			)
			(layer "F.Fab")
		)
		(fp_line
			(start 1.700022 -0.899922)
			(end 1.700022 0.899922)
			(stroke
				(width 0.1)
				(type default)
			)
			(layer "F.Fab")
		)
		(fp_line
			(start 1.700022 0.899922)
			(end -1.700022 0.899922)
			(stroke
				(width 0.1)
				(type default)
			)
			(layer "F.Fab")
		)
		(pad "1" smd rect
			(at -1.4732 0 180)
			(size 1.1684 1.5748)
			(layers "F.Cu" "F.Mask" "F.Paste")
			(net "P52V_HS_FILTER")
		)
		(pad "2" smd rect
			(at 1.4732 0 180)
			(size 1.1684 1.5748)
			(layers "F.Cu" "F.Mask" "F.Paste")
			(net "GND")
		)
	)
	(footprint ""
		(layer "F.Cu")
		(at 279.019 -37.465)
		(property "Reference" "R144"
			(at 0 0 0)
			(layer "F.SilkS")
			(hide yes)
			(effects
				(font
					(size 1.27 1.27)
				)
			)
		)
		(property "Value" ""
			(at 0 0 0)
			(layer "F.Fab")
			(effects
				(font
					(size 1.27 1.27)
				)
			)
		)
		(duplicate_pad_numbers_are_jumpers no)
		(fp_line
			(start -0.7874 -0.4064)
			(end 0.7874 -0.4064)
			(stroke
				(width 0.1524)
				(type default)
			)
			(layer "F.SilkS")
		)
		(fp_line
			(start -0.7874 0.4064)
			(end -0.7874 -0.4064)
			(stroke
				(width 0.1524)
				(type default)
			)
			(layer "F.SilkS")
		)
		(fp_line
			(start 0.7874 -0.4064)
			(end 0.7874 0.4064)
			(stroke
				(width 0.1524)
				(type default)
			)
			(layer "F.SilkS")
		)
		(fp_line
			(start 0.7874 0.4064)
			(end -0.7874 0.4064)
			(stroke
				(width 0.1524)
				(type default)
			)
			(layer "F.SilkS")
		)
		(fp_line
			(start -0.67945 -0.305054)
			(end -0.12065 -0.305054)
			(stroke
				(width 0.1)
				(type default)
			)
			(layer "F.Fab")
		)
		(fp_line
			(start -0.67945 0.3048)
			(end -0.67945 -0.305054)
			(stroke
				(width 0.1)
				(type default)
			)
			(layer "F.Fab")
		)
		(fp_line
			(start -0.12065 -0.305054)
			(end -0.12065 -0.2794)
			(stroke
				(width 0.1)
				(type default)
			)
			(layer "F.Fab")
		)
		(fp_line
			(start -0.12065 -0.2794)
			(end 0.12065 -0.2794)
			(stroke
				(width 0.1)
				(type default)
			)
			(layer "F.Fab")
		)
		(fp_line
			(start -0.12065 0.2794)
			(end -0.12065 0.3048)
			(stroke
				(width 0.1)
				(type default)
			)
			(layer "F.Fab")
		)
		(fp_line
			(start -0.12065 0.3048)
			(end -0.67945 0.3048)
			(stroke
				(width 0.1)
				(type default)
			)
			(layer "F.Fab")
		)
		(fp_line
			(start 0.120396 0.2794)
			(end -0.12065 0.2794)
			(stroke
				(width 0.1)
				(type default)
			)
			(layer "F.Fab")
		)
		(fp_line
			(start 0.120396 0.3048)
			(end 0.120396 0.2794)
			(stroke
				(width 0.1)
				(type default)
			)
			(layer "F.Fab")
		)
		(fp_line
			(start 0.12065 -0.3048)
			(end 0.67945 -0.3048)
			(stroke
				(width 0.1)
				(type default)
			)
			(layer "F.Fab")
		)
		(fp_line
			(start 0.12065 -0.2794)
			(end 0.12065 -0.3048)
			(stroke
				(width 0.1)
				(type default)
			)
			(layer "F.Fab")
		)
		(fp_line
			(start 0.67945 -0.3048)
			(end 0.67945 0.3048)
			(stroke
				(width 0.1)
				(type default)
			)
			(layer "F.Fab")
		)
		(fp_line
			(start 0.67945 0.3048)
			(end 0.120396 0.3048)
			(stroke
				(width 0.1)
				(type default)
			)
			(layer "F.Fab")
		)
		(pad "1" smd circle
			(at -0.40005 0)
			(size 0 0)
			(layers "F.Cu" "F.Mask" "F.Paste")
			(net "SMB_P52V_HSC_SDA")
		)
		(pad "2" smd circle
			(at 0.40005 0)
			(size 0 0)
			(layers "F.Cu" "F.Mask" "F.Paste")
			(net "SMB_CM_HS1_3V3SB_DATI")
		)
	)
)
